(kicad_pcb
	(version 20241229)
	(generator "pcbnew")
	(generator_version "9.0")
	(general
		(thickness 1.294)
		(legacy_teardrops no)
	)
	(paper "A3")
	(title_block
		(title "Kintex 410T devboard")
		(date "2024-04-03")
		(rev "1.1.2")
		(comment 9 "footprints 119-124 of 975")
	)
	(layers
		(0 "F.Cu" mixed)
		(4 "In1.Cu" power)
		(6 "In2.Cu" power)
		(8 "In3.Cu" mixed)
		(10 "In4.Cu" power)
		(12 "In5.Cu" mixed)
		(14 "In6.Cu" power)
		(16 "In7.Cu" mixed)
		(18 "In8.Cu" power)
		(2 "B.Cu" mixed)
		(9 "F.Adhes" user "F.Adhesive")
		(11 "B.Adhes" user "B.Adhesive")
		(13 "F.Paste" user)
		(15 "B.Paste" user)
		(5 "F.SilkS" user "F.Silkscreen")
		(7 "B.SilkS" user "B.Silkscreen")
		(1 "F.Mask" user)
		(3 "B.Mask" user)
		(17 "Dwgs.User" user "User.Drawings")
		(19 "Cmts.User" user "User.Comments")
		(21 "Eco1.User" user "User.Eco1")
		(23 "Eco2.User" user "User.Eco2")
		(25 "Edge.Cuts" user)
		(27 "Margin" user)
		(31 "F.CrtYd" user "F.Courtyard")
		(29 "B.CrtYd" user "B.Courtyard")
		(35 "F.Fab" user)
		(33 "B.Fab" user)
	)
	(footprint "antmicro-footprints:USON-10_2.5x1mm_P0.5mm"
		(layer "F.Cu")
		(at 260.1 101.25 180)
		(descr "USON-10 2.5x1mm_ Pitch 0.5mm")
		(tags "USON-10 2.5x1mm Pitch 0.5mm")
		(property "Reference" "U16"
			(at 0.95 -1.15 270)
			(layer "F.SilkS")
			(effects
				(font
					(size 0.7 0.7)
					(thickness 0.15)
				)
				(justify left bottom)
			)
		)
		(property "Value" "TPD4E05U06QDQARQ1"
			(at 0.018 2.499 180)
			(layer "F.Fab")
			(effects
				(font
					(size 0.7 0.7)
					(thickness 0.15)
				)
				(justify left bottom)
			)
		)
		(property "Description" "ESD protection"
			(at 0 0 180)
			(layer "F.Fab")
			(hide yes)
			(effects
				(font
					(size 1.27 1.27)
					(thickness 0.15)
				)
			)
		)
		(property "Author" "Antmicro"
			(at 520.2 202.5 0)
			(layer "F.Fab")
			(hide yes)
			(effects
				(font
					(size 1 1)
					(thickness 0.15)
				)
			)
		)
		(property "License" "Apache-2.0"
			(at 520.2 202.5 0)
			(layer "F.Fab")
			(hide yes)
			(effects
				(font
					(size 1 1)
					(thickness 0.15)
				)
			)
		)
		(property "MPN" "TPD4E05U06QDQARQ1"
			(at 520.2 202.5 0)
			(layer "F.Fab")
			(hide yes)
			(effects
				(font
					(size 1 1)
					(thickness 0.15)
				)
			)
		)
		(property "Manufacturer" "Texas Instruments"
			(at 520.2 202.5 0)
			(layer "F.Fab")
			(hide yes)
			(effects
				(font
					(size 1 1)
					(thickness 0.15)
				)
			)
		)
		(sheetname "USB PHY")
		(sheetfile "usb-phy.kicad_sch")
		(attr smd)
		(fp_line
			(start 0.498 1.398)
			(end -0.5 1.398)
			(stroke
				(width 0.15)
				(type solid)
			)
			(layer "F.SilkS")
		)
		(fp_line
			(start 0.498 -1.401)
			(end -0.5 -1.401)
			(stroke
				(width 0.15)
				(type solid)
			)
			(layer "F.SilkS")
		)
		(fp_circle
			(center -0.68 -1.27)
			(end -0.63 -1.27)
			(stroke
				(width 0.15)
				(type solid)
			)
			(fill yes)
			(layer "F.SilkS")
		)
		(fp_rect
			(start -0.8 -1.5)
			(end 0.8 1.499)
			(stroke
				(width 0.05)
				(type solid)
			)
			(fill no)
			(layer "F.CrtYd")
		)
		(fp_line
			(start 0.498 -1.25)
			(end 0.498 1.249)
			(stroke
				(width 0.15)
				(type solid)
			)
			(layer "F.Fab")
		)
		(fp_line
			(start 0.498 -1.25)
			(end -0.25 -1.25)
			(stroke
				(width 0.15)
				(type solid)
			)
			(layer "F.Fab")
		)
		(fp_line
			(start -0.25 -1.25)
			(end -0.5 -1)
			(stroke
				(width 0.15)
				(type solid)
			)
			(layer "F.Fab")
		)
		(fp_line
			(start -0.5 1.249)
			(end 0.498 1.249)
			(stroke
				(width 0.15)
				(type solid)
			)
			(layer "F.Fab")
		)
		(fp_line
			(start -0.5 -1)
			(end -0.5 1.249)
			(stroke
				(width 0.15)
				(type solid)
			)
			(layer "F.Fab")
		)
		(pad "1" smd roundrect
			(at -0.387 -1 90)
			(size 0.25 0.55)
			(layers "F.Cu" "F.Mask" "F.Paste")
			(roundrect_rratio 0.25)
			(net 835 "/USB PHY/USB_HOST_CONN_D-")
			(pintype "passive")
		)
		(pad "2" smd roundrect
			(at -0.387 -0.5 90)
			(size 0.25 0.55)
			(layers "F.Cu" "F.Mask" "F.Paste")
			(roundrect_rratio 0.25)
			(net 836 "/USB PHY/USB_HOST_CONN_D+")
			(pintype "passive")
		)
		(pad "3" smd roundrect
			(at -0.387 0 90)
			(size 0.4 0.55)
			(layers "F.Cu" "F.Mask" "F.Paste")
			(roundrect_rratio 0.25)
			(net 1 "GND")
			(pintype "power_in")
		)
		(pad "4" smd roundrect
			(at -0.387 0.498 90)
			(size 0.25 0.55)
			(layers "F.Cu" "F.Mask" "F.Paste")
			(roundrect_rratio 0.25)
			(net 705 "/USB PHY/USB_HOST_VBUS")
			(pintype "passive")
		)
		(pad "5" smd roundrect
			(at -0.387 0.998 90)
			(size 0.25 0.55)
			(layers "F.Cu" "F.Mask" "F.Paste")
			(roundrect_rratio 0.25)
			(net 1144 "unconnected-(U16-Pad5)")
			(pintype "passive+no_connect")
		)
		(pad "6" smd roundrect
			(at 0.385 0.998 90)
			(size 0.25 0.55)
			(layers "F.Cu" "F.Mask" "F.Paste")
			(roundrect_rratio 0.25)
			(net 1144 "unconnected-(U16-Pad5)")
			(pintype "passive+no_connect")
		)
		(pad "7" smd roundrect
			(at 0.385 0.498 90)
			(size 0.25 0.55)
			(layers "F.Cu" "F.Mask" "F.Paste")
			(roundrect_rratio 0.25)
			(net 705 "/USB PHY/USB_HOST_VBUS")
			(pintype "passive")
		)
		(pad "8" smd roundrect
			(at 0.385 0 90)
			(size 0.4 0.55)
			(layers "F.Cu" "F.Mask" "F.Paste")
			(roundrect_rratio 0.25)
			(net 1 "GND")
			(pintype "passive")
		)
		(pad "9" smd roundrect
			(at 0.385 -0.5 90)
			(size 0.25 0.55)
			(layers "F.Cu" "F.Mask" "F.Paste")
			(roundrect_rratio 0.25)
			(net 836 "/USB PHY/USB_HOST_CONN_D+")
			(pintype "passive")
		)
		(pad "10" smd roundrect
			(at 0.385 -1 90)
			(size 0.25 0.55)
			(layers "F.Cu" "F.Mask" "F.Paste")
			(roundrect_rratio 0.25)
			(net 835 "/USB PHY/USB_HOST_CONN_D-")
			(pintype "passive")
		)
	)
	(footprint "antmicro-footprints:Resonator_SMD_Abracon_ABM8G_3.2x2.5mm"
		(layer "F.Cu")
		(at 229.4 149.7 180)
		(property "Reference" "Y3"
			(at -0.5 -2.4 0)
			(layer "F.SilkS")
			(effects
				(font
					(size 0.7 0.7)
					(thickness 0.15)
				)
				(justify left bottom)
			)
		)
		(property "Value" "Resonator_25MHz_ABM8G"
			(at -1.75 2.548 180)
			(layer "F.Fab")
			(effects
				(font
					(size 0.7 0.7)
					(thickness 0.15)
				)
				(justify left bottom)
			)
		)
		(property "Description" "Crystal, 25 MHz, SMD, 3.2mm x 2.5mm, 30 ppm, 18 pF, 20 ppm, ABM8G"
			(at 0 0 180)
			(layer "F.Fab")
			(hide yes)
			(effects
				(font
					(size 1.27 1.27)
					(thickness 0.15)
				)
			)
		)
		(property "Author" "Antmicro"
			(at 458.8 299.4 0)
			(layer "F.Fab")
			(hide yes)
			(effects
				(font
					(size 1 1)
					(thickness 0.15)
				)
			)
		)
		(property "License" "Apache-2.0"
			(at 458.8 299.4 0)
			(layer "F.Fab")
			(hide yes)
			(effects
				(font
					(size 1 1)
					(thickness 0.15)
				)
			)
		)
		(property "MPN" "ABM8G-25.000MHZ-18-D2Y-T3"
			(at 458.8 299.4 0)
			(layer "F.Fab")
			(hide yes)
			(effects
				(font
					(size 1 1)
					(thickness 0.15)
				)
			)
		)
		(property "Manufacturer" "Abracon"
			(at 458.8 299.4 0)
			(layer "F.Fab")
			(hide yes)
			(effects
				(font
					(size 1 1)
					(thickness 0.15)
				)
			)
		)
		(property "Val" "25 MHz"
			(at 458.8 299.4 0)
			(layer "F.Fab")
			(hide yes)
			(effects
				(font
					(size 1 1)
					(thickness 0.15)
				)
			)
		)
		(sheetname "HDMI + Ethernet")
		(sheetfile "hdmi-ethernet.kicad_sch")
		(attr smd)
		(fp_line
			(start 1.6 0.3)
			(end 1.6 -0.2)
			(stroke
				(width 0.15)
				(type solid)
			)
			(layer "F.SilkS")
		)
		(fp_line
			(start -0.35 1.25)
			(end 0.45 1.25)
			(stroke
				(width 0.15)
				(type solid)
			)
			(layer "F.SilkS")
		)
		(fp_line
			(start -0.35 -1.25)
			(end 0.45 -1.25)
			(stroke
				(width 0.15)
				(type solid)
			)
			(layer "F.SilkS")
		)
		(fp_line
			(start -1.6 0.3)
			(end -1.6 -0.2)
			(stroke
				(width 0.15)
				(type solid)
			)
			(layer "F.SilkS")
		)
		(fp_circle
			(center -1.75 1.5)
			(end -1.7 1.5)
			(stroke
				(width 0.15)
				(type solid)
			)
			(fill no)
			(layer "F.SilkS")
		)
		(fp_rect
			(start -1.907 -1.55)
			(end 2.006 1.649)
			(stroke
				(width 0.05)
				(type solid)
			)
			(fill no)
			(layer "F.CrtYd")
		)
		(pad "1" smd roundrect
			(at -1.101 0.949 180)
			(size 1.3 1.1)
			(layers "F.Cu" "F.Mask" "F.Paste")
			(roundrect_rratio 0)
			(chamfer_ratio 0.2)
			(chamfer bottom_left)
			(net 716 "/HDMI + Ethernet/ETH_XI")
			(pintype "passive")
		)
		(pad "2" smd rect
			(at 1.199 0.949 180)
			(size 1.3 1.1)
			(layers "F.Cu" "F.Mask" "F.Paste")
			(net 1 "GND")
			(pinfunction "SH")
			(pintype "passive")
		)
		(pad "3" smd rect
			(at 1.199 -0.85 180)
			(size 1.3 1.1)
			(layers "F.Cu" "F.Mask" "F.Paste")
			(net 719 "/HDMI + Ethernet/ETH_XO")
			(pintype "passive")
		)
		(pad "4" smd rect
			(at -1.101 -0.85 180)
			(size 1.3 1.1)
			(layers "F.Cu" "F.Mask" "F.Paste")
			(net 1 "GND")
			(pinfunction "SH")
			(pintype "passive")
		)
	)
	(footprint "antmicro-footprints:R_0402_1005Metric"
		(layer "F.Cu")
		(at 259.6 129.7)
		(descr "Resistor SMD 0402")
		(tags "resistor SMD 0402")
		(property "Reference" "R192"
			(at -1.05 -6.05 0)
			(layer "F.SilkS")
			(effects
				(font
					(size 0.7 0.7)
					(thickness 0.15)
				)
				(justify left bottom)
			)
		)
		(property "Value" "R_10k_0402"
			(at 0 1.4 0)
			(layer "F.Fab")
			(effects
				(font
					(size 0.7 0.7)
					(thickness 0.15)
				)
				(justify left bottom)
			)
		)
		(property "Description" "SMD Chip Resistor, 10 kohm, ± 1%, 62.5 mW, 0402 [1005 Metric], Thick Film, General Purpose"
			(at 0 0 0)
			(layer "F.Fab")
			(hide yes)
			(effects
				(font
					(size 1.27 1.27)
					(thickness 0.15)
				)
			)
		)
		(property "Author" "Antmicro"
			(at 0 0 0)
			(layer "F.Fab")
			(hide yes)
			(effects
				(font
					(size 1 1)
					(thickness 0.15)
				)
			)
		)
		(property "License" "Apache-2.0"
			(at 0 0 0)
			(layer "F.Fab")
			(hide yes)
			(effects
				(font
					(size 1 1)
					(thickness 0.15)
				)
			)
		)
		(property "MPN" "CR0402-FX-1002GLF"
			(at 0 0 0)
			(layer "F.Fab")
			(hide yes)
			(effects
				(font
					(size 1 1)
					(thickness 0.15)
				)
			)
		)
		(property "Manufacturer" "Bourns"
			(at 0 0 0)
			(layer "F.Fab")
			(hide yes)
			(effects
				(font
					(size 1 1)
					(thickness 0.15)
				)
			)
		)
		(property "Tolerance" "1%"
			(at 0 0 0)
			(layer "F.Fab")
			(hide yes)
			(effects
				(font
					(size 1 1)
					(thickness 0.15)
				)
			)
		)
		(property "Val" "10k"
			(at 0 0 0)
			(layer "F.Fab")
			(hide yes)
			(effects
				(font
					(size 1 1)
					(thickness 0.15)
				)
			)
		)
		(sheetname "USB PHY")
		(sheetfile "usb-phy.kicad_sch")
		(attr smd)
		(fp_rect
			(start -0.925 -0.47)
			(end 0.925 0.47)
			(stroke
				(width 0.05)
				(type default)
			)
			(fill no)
			(layer "F.CrtYd")
		)
		(fp_rect
			(start -0.5 -0.25)
			(end 0.5 0.25)
			(stroke
				(width 0.15)
				(type solid)
			)
			(fill no)
			(layer "F.Fab")
		)
		(pad "1" smd roundrect
			(at -0.48 0)
			(size 0.59 0.64)
			(layers "F.Cu" "F.Mask" "F.Paste")
			(roundrect_rratio 0.25)
			(net 1 "GND")
			(pintype "passive")
		)
		(pad "2" smd roundrect
			(at 0.48 0)
			(size 0.59 0.64)
			(layers "F.Cu" "F.Mask" "F.Paste")
			(roundrect_rratio 0.25)
			(net 943 "Net-(R191-Pad1)")
			(pintype "passive")
		)
	)
	(footprint "antmicro-footprints:R_0402_1005Metric"
		(layer "F.Cu")
		(at 173.570001 84.257501)
		(descr "Resistor SMD 0402")
		(tags "resistor SMD 0402")
		(property "Reference" "R269"
			(at 0.929999 0.342499 0)
			(layer "F.SilkS")
			(effects
				(font
					(size 0.7 0.7)
					(thickness 0.15)
				)
				(justify left bottom)
			)
		)
		(property "Value" "R_33R_0402"
			(at 0 1.4 0)
			(layer "F.Fab")
			(effects
				(font
					(size 0.7 0.7)
					(thickness 0.15)
				)
				(justify left bottom)
			)
		)
		(property "Description" "SMD Chip Resistor, 33 ohm, ± 1%, 62.5 mW, 0402 [1005 Metric], Thick Film, General Purpose"
			(at 0 0 0)
			(layer "F.Fab")
			(hide yes)
			(effects
				(font
					(size 1.27 1.27)
					(thickness 0.15)
				)
			)
		)
		(property "Author" "Antmicro"
			(at 0 0 0)
			(layer "F.Fab")
			(hide yes)
			(effects
				(font
					(size 1 1)
					(thickness 0.15)
				)
			)
		)
		(property "License" "Apache-2.0"
			(at 0 0 0)
			(layer "F.Fab")
			(hide yes)
			(effects
				(font
					(size 1 1)
					(thickness 0.15)
				)
			)
		)
		(property "MPN" "CR0402-FX-33R0GLF"
			(at 0 0 0)
			(layer "F.Fab")
			(hide yes)
			(effects
				(font
					(size 1 1)
					(thickness 0.15)
				)
			)
		)
		(property "Manufacturer" "Bourns"
			(at 0 0 0)
			(layer "F.Fab")
			(hide yes)
			(effects
				(font
					(size 1 1)
					(thickness 0.15)
				)
			)
		)
		(property "Tolerance" "1%"
			(at 0 0 0)
			(layer "F.Fab")
			(hide yes)
			(effects
				(font
					(size 1 1)
					(thickness 0.15)
				)
			)
		)
		(property "Val" "33R"
			(at 0 0 0)
			(layer "F.Fab")
			(hide yes)
			(effects
				(font
					(size 1 1)
					(thickness 0.15)
				)
			)
		)
		(sheetname "FMC+ HSPC")
		(sheetfile "fmc-hspc.kicad_sch")
		(attr smd)
		(fp_rect
			(start -0.925 -0.47)
			(end 0.925 0.47)
			(stroke
				(width 0.05)
				(type default)
			)
			(fill no)
			(layer "F.CrtYd")
		)
		(fp_rect
			(start -0.5 -0.25)
			(end 0.5 0.25)
			(stroke
				(width 0.15)
				(type solid)
			)
			(fill no)
			(layer "F.Fab")
		)
		(pad "1" smd roundrect
			(at -0.48 0)
			(size 0.59 0.64)
			(layers "F.Cu" "F.Mask" "F.Paste")
			(roundrect_rratio 0.25)
			(net 627 "/FMC+ HSPC/GTR_REFCLK0_R_P")
			(pintype "passive")
		)
		(pad "2" smd roundrect
			(at 0.48 0)
			(size 0.59 0.64)
			(layers "F.Cu" "F.Mask" "F.Paste")
			(roundrect_rratio 0.25)
			(net 628 "/FMC+ HSPC/GTX115.REFCLK0_P")
			(pintype "passive")
		)
	)
	(footprint "antmicro-footprints:R_0402_1005Metric"
		(layer "F.Cu")
		(at 212.88 154.7 -90)
		(descr "Resistor SMD 0402")
		(tags "resistor SMD 0402")
		(property "Reference" "R72"
			(at -0.96 0.35 270)
			(layer "F.SilkS")
			(effects
				(font
					(size 0.7 0.7)
					(thickness 0.15)
				)
				(justify left bottom)
			)
		)
		(property "Value" "R_100R_0402"
			(at 0 1.4 270)
			(layer "F.Fab")
			(effects
				(font
					(size 0.7 0.7)
					(thickness 0.15)
				)
				(justify left bottom)
			)
		)
		(property "Description" "SMD Chip Resistor, 100 ohm, ± 1%, 62.5 mW, 0402 [1005 Metric], Thick Film, General Purpose"
			(at 0 0 270)
			(layer "F.Fab")
			(hide yes)
			(effects
				(font
					(size 1.27 1.27)
					(thickness 0.15)
				)
			)
		)
		(property "Author" "Antmicro"
			(at 58.18 367.58 0)
			(layer "F.Fab")
			(hide yes)
			(effects
				(font
					(size 1 1)
					(thickness 0.15)
				)
			)
		)
		(property "DNP" "DNP"
			(at 58.18 367.58 0)
			(layer "F.Fab")
			(hide yes)
			(effects
				(font
					(size 1 1)
					(thickness 0.15)
				)
			)
		)
		(property "License" "Apache-2.0"
			(at 58.18 367.58 0)
			(layer "F.Fab")
			(hide yes)
			(effects
				(font
					(size 1 1)
					(thickness 0.15)
				)
			)
		)
		(property "MPN" "CR0402-FX-1000GLF"
			(at 58.18 367.58 0)
			(layer "F.Fab")
			(hide yes)
			(effects
				(font
					(size 1 1)
					(thickness 0.15)
				)
			)
		)
		(property "Manufacturer" "Bourns"
			(at 58.18 367.58 0)
			(layer "F.Fab")
			(hide yes)
			(effects
				(font
					(size 1 1)
					(thickness 0.15)
				)
			)
		)
		(property "Tolerance" "1%"
			(at 58.18 367.58 0)
			(layer "F.Fab")
			(hide yes)
			(effects
				(font
					(size 1 1)
					(thickness 0.15)
				)
			)
		)
		(property "Val" "100R"
			(at 58.18 367.58 0)
			(layer "F.Fab")
			(hide yes)
			(effects
				(font
					(size 1 1)
					(thickness 0.15)
				)
			)
		)
		(property "dnp" ""
			(at 58.18 367.58 0)
			(layer "F.Fab")
			(hide yes)
			(effects
				(font
					(size 1 1)
					(thickness 0.15)
				)
			)
		)
		(property "exclude_from_bom" ""
			(at 58.18 367.58 0)
			(layer "F.Fab")
			(hide yes)
			(effects
				(font
					(size 1 1)
					(thickness 0.15)
				)
			)
		)
		(sheetname "SPI Flash + SD Card")
		(sheetfile "spi-flash.kicad_sch")
		(attr smd exclude_from_bom)
		(fp_rect
			(start -0.925 -0.47)
			(end 0.925 0.47)
			(stroke
				(width 0.05)
				(type default)
			)
			(fill no)
			(layer "F.CrtYd")
		)
		(fp_rect
			(start -0.5 -0.25)
			(end 0.5 0.25)
			(stroke
				(width 0.15)
				(type solid)
			)
			(fill no)
			(layer "F.Fab")
		)
		(pad "1" smd roundrect
			(at -0.48 0 270)
			(size 0.59 0.64)
			(layers "F.Cu" "F.Mask" "F.Paste")
			(roundrect_rratio 0.25)
			(net 408 "/FPGA Bank 33 & 34/USR_FLASH_0.CLK")
			(pintype "passive")
		)
		(pad "2" smd roundrect
			(at 0.48 0 270)
			(size 0.59 0.64)
			(layers "F.Cu" "F.Mask" "F.Paste")
			(roundrect_rratio 0.25)
			(net 26 "+1V8")
			(pintype "passive")
		)
	)
	(footprint "antmicro-footprints:R_0603_1608Metric"
		(layer "F.Cu")
		(at 174.9 162.5)
		(descr "Resistor SMD 0603")
		(tags "resistor SMD 0603")
		(property "Reference" "R289"
			(at -3.85 0.35 0)
			(layer "F.SilkS")
			(effects
				(font
					(size 0.7 0.7)
					(thickness 0.15)
				)
				(justify left bottom)
			)
		)
		(property "Value" "R_0R_22.4A_0603"
			(at 0 1.6 0)
			(layer "F.Fab")
			(effects
				(font
					(size 0.7 0.7)
					(thickness 0.15)
				)
				(justify left bottom)
			)
		)
		(property "Description" "SMD Chip Resistor"
			(at 0 0 0)
			(layer "F.Fab")
			(hide yes)
			(effects
				(font
					(size 1.27 1.27)
					(thickness 0.15)
				)
			)
		)
		(property "Author" "Antmicro"
			(at 0 0 0)
			(layer "F.Fab")
			(hide yes)
			(effects
				(font
					(size 1 1)
					(thickness 0.15)
				)
			)
		)
		(property "License" "Apache-2.0"
			(at 0 0 0)
			(layer "F.Fab")
			(hide yes)
			(effects
				(font
					(size 1 1)
					(thickness 0.15)
				)
			)
		)
		(property "MPN" "PMR03EZPJ000"
			(at 0 0 0)
			(layer "F.Fab")
			(hide yes)
			(effects
				(font
					(size 1 1)
					(thickness 0.15)
				)
			)
		)
		(property "Manufacturer" "ROHM Semiconductor"
			(at 0 0 0)
			(layer "F.Fab")
			(hide yes)
			(effects
				(font
					(size 1 1)
					(thickness 0.15)
				)
			)
		)
		(property "Max. Curr." "22.4A"
			(at 0 0 0)
			(layer "F.Fab")
			(hide yes)
			(effects
				(font
					(size 1 1)
					(thickness 0.15)
				)
			)
		)
		(property "Tolerance" "template_tolerance"
			(at 0 0 0)
			(layer "F.Fab")
			(hide yes)
			(effects
				(font
					(size 1 1)
					(thickness 0.15)
				)
			)
		)
		(property "Val" "0R"
			(at 0 0 0)
			(layer "F.Fab")
			(hide yes)
			(effects
				(font
					(size 1 1)
					(thickness 0.15)
				)
			)
		)
		(sheetname "DC-DC Converters")
		(sheetfile "dc-dc.kicad_sch")
		(attr smd)
		(fp_line
			(start -0.15 -0.4)
			(end 0.15 -0.4)
			(stroke
				(width 0.15)
				(type solid)
			)
			(layer "F.SilkS")
		)
		(fp_line
			(start -0.15 0.4)
			(end 0.15 0.4)
			(stroke
				(width 0.15)
				(type solid)
			)
			(layer "F.SilkS")
		)
		(fp_rect
			(start -1.25 -0.65)
			(end 1.25 0.65)
			(stroke
				(width 0.05)
				(type solid)
			)
			(fill no)
			(layer "F.CrtYd")
		)
		(fp_rect
			(start -0.8 -0.4)
			(end 0.8 0.4)
			(stroke
				(width 0.15)
				(type solid)
			)
			(fill no)
			(layer "F.Fab")
		)
		(pad "1" smd roundrect
			(at -0.7 0)
			(size 0.8 1)
			(layers "F.Cu" "F.Mask" "F.Paste")
			(roundrect_rratio 0.2)
			(net 735 "/DC-DC Converters/3V3_local")
			(pintype "passive")
		)
		(pad "2" smd roundrect
			(at 0.7 0)
			(size 0.8 1)
			(layers "F.Cu" "F.Mask" "F.Paste")
			(roundrect_rratio 0.2)
			(net 24 "+3V3")
			(pintype "passive")
		)
	)
)
